# BASEBOARD_FAB2 (Tioga Pass) — schematic netlist excerpt (pin names and nets, part order shuffled) for the footprints in the layout excerpt that follows; sources: Cadence DE-HDL packaged netlist, KiCad conversion of Wiwynn_Tioga_Pass_MB.brd

R6W24  RES  4.75K 1% CHIP  pkg 0402  page 247 : A = P3V3_STBY ; B = SMB_PMBUS_BMC_STBY_LVC3_SDA_R1

U1W3  PCA9617  IC  pkg SSOP  page 176
  VCCA  = P3V3_STBY
  SCLA  = SMB_DEBUG_STBY_LVC3_SCL_CONN
  SDAA  = SMB_DEBUG_STBY_LVC3_SDA_CONN
  EN  = DEBUG_CARD2_PRSNT
  SDAB  = SMB_DEBUG_STBY_LVC3_SDA_R1
  SCLB  = SMB_DEBUG_STBY_LVC3_SCL_R1
  VCCB  = P3V3_STBY

(kicad_pcb
	(version 20260206)
	(generator "pcbnew")
	(generator_version "10.0")
	(general
		(thickness 1.6)
		(legacy_teardrops no)
	)
	(paper "A4")
	(title_block
		(title "Wiwynn_Tioga_Pass_MB.brd")
		(comment 1 "Tioga Pass / footprints 2885-2886 of 4770")
	)
	(layers
		(0 "F.Cu" signal "TOP")
		(4 "In1.Cu" signal "L2GND")
		(6 "In2.Cu" signal "L3")
		(8 "In3.Cu" signal "L4GND")
		(10 "In4.Cu" signal "L5")
		(12 "In5.Cu" signal "L6GND")
		(14 "In6.Cu" signal "L7VCC")
		(16 "In7.Cu" signal "L8VCC")
		(18 "In8.Cu" signal "L9GND")
		(20 "In9.Cu" signal "L10")
		(22 "In10.Cu" signal "L11GND")
		(24 "In11.Cu" signal "L12")
		(26 "In12.Cu" signal "L13GND")
		(2 "B.Cu" signal "BOTTOM")
		(9 "F.Adhes" user "F.Adhesive")
		(11 "B.Adhes" user "B.Adhesive")
		(13 "F.Paste" user "Package Geometry/Pastemask Top")
		(15 "B.Paste" user "Package Geometry/Pastemask Bottom")
		(5 "F.SilkS" user "Ref Des/Silkscreen Top")
		(7 "B.SilkS" user "Ref Des/Silkscreen Bottom")
		(1 "F.Mask" user "Board Geometry/Soldermask Top")
		(3 "B.Mask" user "Board Geometry/Soldermask Bottom")
		(17 "Dwgs.User" user "User.Drawings")
		(19 "Cmts.User" user "User.Comments")
		(21 "Eco1.User" user "User.Eco1")
		(23 "Eco2.User" user "User.Eco2")
		(25 "Edge.Cuts" user "Board Geometry/Outline")
		(27 "Margin" user)
		(31 "F.CrtYd" user "Package Geometry/Place Bound Top")
		(29 "B.CrtYd" user "Package Geometry/Place Bound Bottom")
		(35 "F.Fab" user "Ref Des/Assembly Top")
		(33 "B.Fab" user "Ref Des/Assembly Bottom")
	)
	(footprint ""
		(layer "B.Cu")
		(at 474.14942 -134.00024 90)
		(property "Reference" "U1W3"
			(at -2.2733 -1.09728 90)
			(unlocked yes)
			(layer "B.SilkS")
			(effects
				(font
					(size 0.4064 0.254)
					(thickness 0.1524)
				)
				(justify mirror)
			)
		)
		(property "Value" ""
			(at 0 0 90)
			(layer "B.Fab")
			(effects
				(font
					(size 1.27 1.27)
				)
				(justify mirror)
			)
		)
		(duplicate_pad_numbers_are_jumpers no)
		(fp_line
			(start -3.225292 -0.57404)
			(end -1.352804 -0.57404)
			(stroke
				(width 0.1524)
				(type default)
			)
			(layer "B.SilkS")
		)
		(fp_line
			(start -3.225038 2.52476)
			(end -1.348486 2.52476)
			(stroke
				(width 0.1524)
				(type default)
			)
			(layer "B.SilkS")
		)
		(fp_circle
			(center 1.971802 -0.212852)
			(end 1.971802 -0.085852)
			(stroke
				(width 0.254)
				(type default)
			)
			(fill no)
			(layer "B.SilkS")
		)
		(fp_poly
			(pts
				(xy -0.7366 -0.57404) (xy -3.8354 -0.57404) (xy -3.8354 2.52476) (xy -0.7366 2.52476)
			)
			(stroke
				(width 0)
				(type default)
			)
			(fill no)
			(layer "B.CrtYd")
		)
		(fp_line
			(start -0.7366 -0.57404)
			(end -3.8354 -0.57404)
			(stroke
				(width 0.1)
				(type default)
			)
			(layer "B.Fab")
		)
		(fp_line
			(start -3.8354 -0.57404)
			(end -3.8354 2.52476)
			(stroke
				(width 0.1)
				(type default)
			)
			(layer "B.Fab")
		)
		(fp_line
			(start -0.7366 2.52476)
			(end -0.7366 -0.57404)
			(stroke
				(width 0.1)
				(type default)
			)
			(layer "B.Fab")
		)
		(fp_line
			(start -3.8354 2.52476)
			(end -0.7366 2.52476)
			(stroke
				(width 0.1)
				(type default)
			)
			(layer "B.Fab")
		)
		(fp_circle
			(center 1.454404 -0.556514)
			(end 1.454404 -0.429514)
			(stroke
				(width 0.254)
				(type default)
			)
			(fill no)
			(layer "B.Fab")
		)
		(pad "1" smd rect
			(at 0 0 270)
			(size 1.778 0.4572)
			(layers "B.Cu" "B.Mask" "B.Paste")
			(net "P3V3_STBY")
		)
		(pad "2" smd rect
			(at 0 0.65024 270)
			(size 1.778 0.4572)
			(layers "B.Cu" "B.Mask" "B.Paste")
			(net "SMB_DEBUG_STBY_LVC3_SCL_CONN")
		)
		(pad "3" smd rect
			(at 0 1.30048 270)
			(size 1.778 0.4572)
			(layers "B.Cu" "B.Mask" "B.Paste")
			(net "SMB_DEBUG_STBY_LVC3_SDA_CONN")
		)
		(pad "4" smd rect
			(at 0 1.95072 270)
			(size 1.778 0.4572)
			(layers "B.Cu" "B.Mask" "B.Paste")
			(net "GND")
		)
		(pad "5" smd rect
			(at -4.572 1.95072 270)
			(size 1.778 0.4572)
			(layers "B.Cu" "B.Mask" "B.Paste")
			(net "DEBUG_CARD2_PRSNT")
		)
		(pad "6" smd rect
			(at -4.572 1.30048 270)
			(size 1.778 0.4572)
			(layers "B.Cu" "B.Mask" "B.Paste")
			(net "SMB_DEBUG_STBY_LVC3_SDA_R1")
		)
		(pad "7" smd rect
			(at -4.572 0.65024 270)
			(size 1.778 0.4572)
			(layers "B.Cu" "B.Mask" "B.Paste")
			(net "SMB_DEBUG_STBY_LVC3_SCL_R1")
		)
		(pad "8" smd rect
			(at -4.572 0 270)
			(size 1.778 0.4572)
			(layers "B.Cu" "B.Mask" "B.Paste")
			(net "P3V3_STBY")
		)
	)
	(footprint ""
		(layer "B.Cu")
		(at 408.6225 -109.22 -90)
		(property "Reference" "R6W24"
			(at 0.8382 -0.67818 270)
			(unlocked yes)
			(layer "B.SilkS")
			(effects
				(font
					(size 0.4064 0.254)
					(thickness 0.1524)
				)
				(justify left mirror)
			)
		)
		(property "Value" ""
			(at 0 0 90)
			(layer "B.Fab")
			(effects
				(font
					(size 1.27 1.27)
				)
				(justify mirror)
			)
		)
		(duplicate_pad_numbers_are_jumpers no)
		(fp_poly
			(pts
				(xy 0.2794 -0.1016) (xy -0.2794 -0.1016) (xy -0.2794 0.9906) (xy 0.2794 0.9906)
			)
			(stroke
				(width 0)
				(type default)
			)
			(fill no)
			(layer "B.CrtYd")
		)
		(fp_line
			(start -0.2794 0.9906)
			(end -0.2794 -0.1016)
			(stroke
				(width 0.1)
				(type default)
			)
			(layer "B.Fab")
		)
		(fp_line
			(start 0.2794 0.9906)
			(end -0.2794 0.9906)
			(stroke
				(width 0.1)
				(type default)
			)
			(layer "B.Fab")
		)
		(fp_line
			(start -0.2794 -0.1016)
			(end 0.2794 -0.1016)
			(stroke
				(width 0.1)
				(type default)
			)
			(layer "B.Fab")
		)
		(fp_line
			(start 0.2794 -0.1016)
			(end 0.2794 0.9906)
			(stroke
				(width 0.1)
				(type default)
			)
			(layer "B.Fab")
		)
		(pad "1" smd rect
			(at 0 0 90)
			(size 0.508 0.508)
			(layers "B.Cu" "B.Mask" "B.Paste")
			(net "P3V3_STBY")
		)
		(pad "2" smd rect
			(at 0 0.889 90)
			(size 0.508 0.508)
			(layers "B.Cu" "B.Mask" "B.Paste")
			(net "SMB_PMBUS_BMC_STBY_LVC3_SDA_R1")
		)
		(zone
			(layer "B.Cu")
			(hatch none 0.5)
			(connect_pads
				(clearance 0)
			)
			(min_thickness 0.25)
			(keepout
				(tracks not_allowed)
				(vias allowed)
				(pads allowed)
				(copperpour not_allowed)
				(footprints allowed)
			)
			(placement
				(enabled no)
				(sheetname "")
			)
			(fill
				(thermal_gap 0.5)
				(thermal_bridge_width 0.5)
				(island_removal_mode 0)
			)
			(polygon
				(pts
					(xy 407.9875 -108.966) (xy 407.9875 -109.474) (xy 408.3685 -109.474) (xy 408.3685 -108.966)
				)
			)
		)
		(zone
			(layer "B.Cu")
			(hatch none 0.5)
			(connect_pads
				(clearance 0)
			)
			(min_thickness 0.25)
			(keepout
				(tracks allowed)
				(vias not_allowed)
				(pads allowed)
				(copperpour not_allowed)
				(footprints allowed)
			)
			(placement
				(enabled no)
				(sheetname "")
			)
			(fill
				(thermal_gap 0.5)
				(thermal_bridge_width 0.5)
				(island_removal_mode 0)
			)
			(polygon
				(pts
					(xy 408.3685 -108.966) (xy 408.3685 -109.474) (xy 407.9875 -109.474) (xy 407.9875 -108.966)
				)
			)
		)
	)
)
